#ISCELL
  mstr_misc dns *
  *
#ISCELL
  pure_quanta quanta_title_block_c *
  *
#CELL
  pure_quanta lcmxo3lf2100c5bg256c *
  page35_i1
#ISCELL
  standard offpage *
  page35_i10
#CELL
  pure_quanta q_res *
  page35_i100
#ISCELL
  standard offpage *
  page35_i106
#ISCELL
  standard offpage *
  page35_i109
#ISCELL
  standard offpage *
  page35_i11
#ISCELL
  standard offpage *
  page35_i110
#ISCELL
  standard offpage *
  page35_i111
#ISCELL
  standard offpage *
  page35_i114
#ISCELL
  standard offpage *
  page35_i115
#ISCELL
  standard offpage *
  page35_i116
#ISCELL
  standard offpage *
  page35_i117
#ISCELL
  standard offpage *
  page35_i118
#ISCELL
  standard offpage *
  page35_i119
#ISCELL
  standard offpage *
  page35_i12
#ISCELL
  standard offpage *
  page35_i121
#ISCELL
  logical_power universal_power *
  page35_i122
#ISCELL
  logical_power universal_power *
  page35_i123
#ISCELL
  standard offpage *
  page35_i124
#ISCELL
  standard offpage *
  page35_i125
#ISCELL
  standard offpage *
  page35_i13
#CELL
  pure_quanta q_res *
  page35_i131
#ISCELL
  standard offpage *
  page35_i132
#ISCELL
  logical_power vccaux15 *
  page35_i133
#ISCELL
  standard offpage *
  page35_i134
#CELL
  pure_quanta q_res *
  page35_i136
#CELL
  pure_quanta q_res *
  page35_i137
#CELL
  pure_quanta q_res *
  page35_i138
#CELL
  pure_quanta q_res *
  page35_i139
#ISCELL
  standard offpage *
  page35_i14
#CELL
  pure_quanta q_res *
  page35_i140
#CELL
  pure_quanta q_res *
  page35_i141
#CELL
  pure_quanta q_res *
  page35_i142
#CELL
  pure_quanta q_res *
  page35_i143
#CELL
  pure_quanta q_res *
  page35_i144
#CELL
  pure_quanta q_res *
  page35_i145
#CELL
  pure_quanta q_res *
  page35_i146
#CELL
  pure_quanta q_res *
  page35_i147
#CELL
  pure_quanta q_res *
  page35_i148
#CELL
  pure_quanta q_res *
  page35_i149
#ISCELL
  standard offpage *
  page35_i15
#CELL
  pure_quanta q_diode *
  page35_i150
#CELL
  pure_quanta q_res *
  page35_i151
#ISCELL
  logical_power vccaux15 *
  page35_i152
#ISCELL
  standard offpage *
  page35_i153
#ISCELL
  standard offpage *
  page35_i154
#ISCELL
  standard offpage *
  page35_i16
#ISCELL
  standard offpage *
  page35_i17
#ISCELL
  standard offpage *
  page35_i18
#CELL
  pure_quanta q_res *
  page35_i2
#ISCELL
  standard offpage *
  page35_i21
#ISCELL
  standard offpage *
  page35_i23
#CELL
  pure_quanta q_res *
  page35_i3
#CELL
  pure_quanta q_res *
  page35_i4
#CELL
  pure_quanta q_res *
  page35_i5
#ISCELL
  standard offpage *
  page35_i52
#ISCELL
  standard offpage *
  page35_i53
#ISCELL
  standard offpage *
  page35_i54
#ISCELL
  standard offpage *
  page35_i55
#ISCELL
  standard offpage *
  page35_i57
#ISCELL
  standard offpage *
  page35_i58
#ISCELL
  standard offpage *
  page35_i59
#ISCELL
  standard offpage *
  page35_i60
#ISCELL
  standard offpage *
  page35_i61
#ISCELL
  standard offpage *
  page35_i62
#ISCELL
  standard offpage *
  page35_i63
#CELL
  pure_quanta q_res *
  page35_i76
#ISCELL
  standard offpage *
  page35_i8
#CELL
  pure_quanta q_res *
  page35_i80
#ISCELL
  standard offpage *
  page35_i84
#ISCELL
  standard offpage *
  page35_i85
#CELL
  pure_quanta q_res *
  page35_i88
#ISCELL
  standard offpage *
  page35_i89
#ISCELL
  standard offpage *
  page35_i9
#CELL
  pure_quanta q_res *
  page35_i95
#CELL
  pure_quanta q_res *
  page35_i98
#CELL
  pure_quanta q_res *
  page35_i99
